# T6G (Grand Teton) — schematic netlist excerpt (pin names and nets, part order shuffled) for the footprints in the layout excerpt that follows; sources: Cadence DE-HDL packaged netlist, KiCad conversion of 04192023_DAF0TMB3IC0_F0TG_MB_C_brd_V02_OCP.brd

C2645  Q_CAP  22UF 4V 20% X6S  pkg C0402  page 70 : A = PVDD11_S3_P0 ; B = GND
R146  Q_RES  0 5% EMPTY  pkg 0402LF  page 161 : A = SMB_CPU0_CPU1_APML_MUX1_SCL ; B = SMB_APML_CPU1_R_SCL

(kicad_pcb
	(version 20260206)
	(generator "pcbnew")
	(generator_version "10.0")
	(general
		(thickness 1.6)
		(legacy_teardrops no)
	)
	(paper "A4")
	(title_block
		(title "04192023_DAF0TMB3IC0_F0TG_MB_C_brd_V02_OCP.brd")
		(comment 1 "Grand Teton / footprints 8188-8189 of 8354")
	)
	(layers
		(0 "F.Cu" signal "TOP")
		(4 "In1.Cu" signal "GND")
		(6 "In2.Cu" signal "IN1")
		(8 "In3.Cu" signal "GND1")
		(10 "In4.Cu" signal "IN2")
		(12 "In5.Cu" signal "GND2")
		(14 "In6.Cu" signal "IN3")
		(16 "In7.Cu" signal "GND3")
		(18 "In8.Cu" signal "VCC")
		(20 "In9.Cu" signal "VCC1")
		(22 "In10.Cu" signal "GND4")
		(24 "In11.Cu" signal "IN4")
		(26 "In12.Cu" signal "GND5")
		(28 "In13.Cu" signal "IN5")
		(30 "In14.Cu" signal "GND6")
		(32 "In15.Cu" signal "IN6")
		(34 "In16.Cu" signal "GND7")
		(2 "B.Cu" signal "BOTTOM")
		(9 "F.Adhes" user "F.Adhesive")
		(11 "B.Adhes" user "B.Adhesive")
		(13 "F.Paste" user "Package Geometry/Pastemask Top")
		(15 "B.Paste" user "Package Geometry/Pastemask Bottom")
		(5 "F.SilkS" user "Ref Des/Silkscreen Top")
		(7 "B.SilkS" user "Ref Des/Silkscreen Bottom")
		(1 "F.Mask" user "Board Geometry/Soldermask Top")
		(3 "B.Mask" user "Board Geometry/Soldermask Bottom")
		(17 "Dwgs.User" user "User.Drawings")
		(19 "Cmts.User" user "User.Comments")
		(21 "Eco1.User" user "User.Eco1")
		(23 "Eco2.User" user "User.Eco2")
		(25 "Edge.Cuts" user "Board Geometry/Outline")
		(27 "Margin" user)
		(31 "F.CrtYd" user "Package Geometry/Place Bound Top")
		(29 "B.CrtYd" user "Package Geometry/Place Bound Bottom")
		(35 "F.Fab" user "Ref Des/Assembly Top")
		(33 "B.Fab" user "Ref Des/Assembly Bottom")
	)
	(footprint ""
		(layer "B.Cu")
		(at 367.614454 -264.35431)
		(property "Reference" "C2645"
			(at 0 0 0)
			(layer "B.SilkS")
			(hide yes)
			(effects
				(font
					(size 1.27 1.27)
				)
				(justify mirror)
			)
		)
		(property "Value" ""
			(at 0 0 0)
			(layer "B.Fab")
			(effects
				(font
					(size 1.27 1.27)
				)
				(justify mirror)
			)
		)
		(duplicate_pad_numbers_are_jumpers no)
		(fp_line
			(start -0.7874 -0.4064)
			(end -0.7874 0.4064)
			(stroke
				(width 0.1524)
				(type default)
			)
			(layer "B.SilkS")
		)
		(fp_line
			(start -0.7874 0.4064)
			(end 0.7874 0.4064)
			(stroke
				(width 0.1524)
				(type default)
			)
			(layer "B.SilkS")
		)
		(fp_line
			(start 0.7874 -0.4064)
			(end -0.7874 -0.4064)
			(stroke
				(width 0.1524)
				(type default)
			)
			(layer "B.SilkS")
		)
		(fp_line
			(start 0.7874 0.4064)
			(end 0.7874 -0.4064)
			(stroke
				(width 0.1524)
				(type default)
			)
			(layer "B.SilkS")
		)
		(fp_line
			(start -0.67945 -0.3048)
			(end -0.67945 0.3048)
			(stroke
				(width 0.1)
				(type default)
			)
			(layer "B.Fab")
		)
		(fp_line
			(start -0.67945 0.3048)
			(end -0.120396 0.3048)
			(stroke
				(width 0.1)
				(type default)
			)
			(layer "B.Fab")
		)
		(fp_line
			(start -0.12065 -0.3048)
			(end -0.67945 -0.3048)
			(stroke
				(width 0.1)
				(type default)
			)
			(layer "B.Fab")
		)
		(fp_line
			(start -0.12065 -0.2794)
			(end -0.12065 -0.3048)
			(stroke
				(width 0.1)
				(type default)
			)
			(layer "B.Fab")
		)
		(fp_line
			(start -0.120396 0.2794)
			(end 0.12065 0.2794)
			(stroke
				(width 0.1)
				(type default)
			)
			(layer "B.Fab")
		)
		(fp_line
			(start -0.120396 0.3048)
			(end -0.120396 0.2794)
			(stroke
				(width 0.1)
				(type default)
			)
			(layer "B.Fab")
		)
		(fp_line
			(start 0.12065 -0.305054)
			(end 0.12065 -0.2794)
			(stroke
				(width 0.1)
				(type default)
			)
			(layer "B.Fab")
		)
		(fp_line
			(start 0.12065 -0.2794)
			(end -0.12065 -0.2794)
			(stroke
				(width 0.1)
				(type default)
			)
			(layer "B.Fab")
		)
		(fp_line
			(start 0.12065 0.2794)
			(end 0.12065 0.3048)
			(stroke
				(width 0.1)
				(type default)
			)
			(layer "B.Fab")
		)
		(fp_line
			(start 0.12065 0.3048)
			(end 0.67945 0.3048)
			(stroke
				(width 0.1)
				(type default)
			)
			(layer "B.Fab")
		)
		(fp_line
			(start 0.67945 -0.305054)
			(end 0.12065 -0.305054)
			(stroke
				(width 0.1)
				(type default)
			)
			(layer "B.Fab")
		)
		(fp_line
			(start 0.67945 0.3048)
			(end 0.67945 -0.305054)
			(stroke
				(width 0.1)
				(type default)
			)
			(layer "B.Fab")
		)
		(pad "1" smd circle
			(at 0.40005 0 180)
			(size 0 0)
			(layers "B.Cu" "B.Mask" "B.Paste")
			(net "PVDD11_S3_P0")
		)
		(pad "2" smd circle
			(at -0.40005 0 180)
			(size 0 0)
			(layers "B.Cu" "B.Mask" "B.Paste")
			(net "GND")
		)
	)
	(footprint ""
		(layer "B.Cu")
		(at 232.918 -232.156 -90)
		(property "Reference" "R146"
			(at 0 0 90)
			(layer "B.SilkS")
			(hide yes)
			(effects
				(font
					(size 1.27 1.27)
				)
				(justify mirror)
			)
		)
		(property "Value" ""
			(at 0 0 90)
			(layer "B.Fab")
			(effects
				(font
					(size 1.27 1.27)
				)
				(justify mirror)
			)
		)
		(duplicate_pad_numbers_are_jumpers no)
		(fp_line
			(start -0.7874 0.4064)
			(end 0.7874 0.4064)
			(stroke
				(width 0.1524)
				(type default)
			)
			(layer "B.SilkS")
		)
		(fp_line
			(start 0.7874 0.4064)
			(end 0.7874 -0.4064)
			(stroke
				(width 0.1524)
				(type default)
			)
			(layer "B.SilkS")
		)
		(fp_line
			(start -0.7874 -0.4064)
			(end -0.7874 0.4064)
			(stroke
				(width 0.1524)
				(type default)
			)
			(layer "B.SilkS")
		)
		(fp_line
			(start 0.7874 -0.4064)
			(end -0.7874 -0.4064)
			(stroke
				(width 0.1524)
				(type default)
			)
			(layer "B.SilkS")
		)
		(fp_line
			(start -0.67945 0.3048)
			(end -0.120396 0.3048)
			(stroke
				(width 0.1)
				(type default)
			)
			(layer "B.Fab")
		)
		(fp_line
			(start -0.120396 0.3048)
			(end -0.120396 0.2794)
			(stroke
				(width 0.1)
				(type default)
			)
			(layer "B.Fab")
		)
		(fp_line
			(start 0.12065 0.3048)
			(end 0.67945 0.3048)
			(stroke
				(width 0.1)
				(type default)
			)
			(layer "B.Fab")
		)
		(fp_line
			(start 0.67945 0.3048)
			(end 0.67945 -0.305054)
			(stroke
				(width 0.1)
				(type default)
			)
			(layer "B.Fab")
		)
		(fp_line
			(start -0.120396 0.2794)
			(end 0.12065 0.2794)
			(stroke
				(width 0.1)
				(type default)
			)
			(layer "B.Fab")
		)
		(fp_line
			(start 0.12065 0.2794)
			(end 0.12065 0.3048)
			(stroke
				(width 0.1)
				(type default)
			)
			(layer "B.Fab")
		)
		(fp_line
			(start -0.12065 -0.2794)
			(end -0.12065 -0.3048)
			(stroke
				(width 0.1)
				(type default)
			)
			(layer "B.Fab")
		)
		(fp_line
			(start 0.12065 -0.2794)
			(end -0.12065 -0.2794)
			(stroke
				(width 0.1)
				(type default)
			)
			(layer "B.Fab")
		)
		(fp_line
			(start -0.67945 -0.3048)
			(end -0.67945 0.3048)
			(stroke
				(width 0.1)
				(type default)
			)
			(layer "B.Fab")
		)
		(fp_line
			(start -0.12065 -0.3048)
			(end -0.67945 -0.3048)
			(stroke
				(width 0.1)
				(type default)
			)
			(layer "B.Fab")
		)
		(fp_line
			(start 0.12065 -0.305054)
			(end 0.12065 -0.2794)
			(stroke
				(width 0.1)
				(type default)
			)
			(layer "B.Fab")
		)
		(fp_line
			(start 0.67945 -0.305054)
			(end 0.12065 -0.305054)
			(stroke
				(width 0.1)
				(type default)
			)
			(layer "B.Fab")
		)
		(pad "1" smd circle
			(at 0.40005 0 90)
			(size 0 0)
			(layers "B.Cu" "B.Mask" "B.Paste")
			(net "SMB_CPU0_CPU1_APML_MUX1_SCL")
		)
		(pad "2" smd circle
			(at -0.40005 0 90)
			(size 0 0)
			(layers "B.Cu" "B.Mask" "B.Paste")
			(net "SMB_APML_CPU1_R_SCL")
		)
	)
)
